# BASEBOARD_FAB2 (Tioga Pass) — schematic netlist excerpt (pin names and nets, part order shuffled) for the footprints in the layout excerpt that follows; sources: Cadence DE-HDL packaged netlist, KiCad conversion of Wiwynn_Tioga_Pass_MB.brd

R2U28  RES  0.0 5% CHIP  pkg 0402  page 107 : A = P3E_CPU0_PE1_SS_RXP<7> ; B = P3E_CPU0_PE1_SS_R_RXP<7>
C3M16  CAP  10UF 16V 10% X6S  pkg 0805  page 232 : A = VR_FET_SW_P12V_STBY_PVPP_DEF ; B = GND
C6N1  CAPP  470UF 2.5V 20% ALUM  pkg 3018  page 205 : A = PVSA_CPU0 ; B = GND

(kicad_pcb
	(version 20260206)
	(generator "pcbnew")
	(generator_version "10.0")
	(general
		(thickness 1.6)
		(legacy_teardrops no)
	)
	(paper "A4")
	(title_block
		(title "Wiwynn_Tioga_Pass_MB.brd")
		(comment 1 "Tioga Pass / footprints 3901-3903 of 4770")
	)
	(layers
		(0 "F.Cu" signal "TOP")
		(4 "In1.Cu" signal "L2GND")
		(6 "In2.Cu" signal "L3")
		(8 "In3.Cu" signal "L4GND")
		(10 "In4.Cu" signal "L5")
		(12 "In5.Cu" signal "L6GND")
		(14 "In6.Cu" signal "L7VCC")
		(16 "In7.Cu" signal "L8VCC")
		(18 "In8.Cu" signal "L9GND")
		(20 "In9.Cu" signal "L10")
		(22 "In10.Cu" signal "L11GND")
		(24 "In11.Cu" signal "L12")
		(26 "In12.Cu" signal "L13GND")
		(2 "B.Cu" signal "BOTTOM")
		(9 "F.Adhes" user "F.Adhesive")
		(11 "B.Adhes" user "B.Adhesive")
		(13 "F.Paste" user "Package Geometry/Pastemask Top")
		(15 "B.Paste" user "Package Geometry/Pastemask Bottom")
		(5 "F.SilkS" user "Ref Des/Silkscreen Top")
		(7 "B.SilkS" user "Ref Des/Silkscreen Bottom")
		(1 "F.Mask" user "Board Geometry/Soldermask Top")
		(3 "B.Mask" user "Board Geometry/Soldermask Bottom")
		(17 "Dwgs.User" user "User.Drawings")
		(19 "Cmts.User" user "User.Comments")
		(21 "Eco1.User" user "User.Eco1")
		(23 "Eco2.User" user "User.Eco2")
		(25 "Edge.Cuts" user "Board Geometry/Outline")
		(27 "Margin" user)
		(31 "F.CrtYd" user "Package Geometry/Place Bound Top")
		(29 "B.CrtYd" user "Package Geometry/Place Bound Bottom")
		(35 "F.Fab" user "Ref Des/Assembly Top")
		(33 "B.Fab" user "Ref Des/Assembly Bottom")
	)
	(footprint ""
		(layer "B.Cu")
		(at 351.663 -133.223 180)
		(property "Reference" "C3M16"
			(at 0 0 0)
			(layer "B.SilkS")
			(hide yes)
			(effects
				(font
					(size 1.27 1.27)
				)
				(justify mirror)
			)
		)
		(property "Value" ""
			(at 0 0 0)
			(layer "B.Fab")
			(effects
				(font
					(size 1.27 1.27)
				)
				(justify mirror)
			)
		)
		(duplicate_pad_numbers_are_jumpers no)
		(fp_poly
			(pts
				(xy 0.7239 -0.2159) (xy -0.7239 -0.2159) (xy -0.7239 1.9939) (xy 0.7239 1.9939)
			)
			(stroke
				(width 0)
				(type default)
			)
			(fill no)
			(layer "B.CrtYd")
		)
		(fp_line
			(start 0.7239 1.9939)
			(end -0.7239 1.9939)
			(stroke
				(width 0.1)
				(type default)
			)
			(layer "B.Fab")
		)
		(fp_line
			(start 0.7239 -0.2159)
			(end 0.7239 1.9939)
			(stroke
				(width 0.1)
				(type default)
			)
			(layer "B.Fab")
		)
		(fp_line
			(start -0.7239 1.9939)
			(end -0.7239 -0.2159)
			(stroke
				(width 0.1)
				(type default)
			)
			(layer "B.Fab")
		)
		(fp_line
			(start -0.7239 -0.2159)
			(end 0.7239 -0.2159)
			(stroke
				(width 0.1)
				(type default)
			)
			(layer "B.Fab")
		)
		(pad "1" smd rect
			(at 0 0)
			(size 1.27 1.016)
			(layers "B.Cu" "B.Mask" "B.Paste")
			(net "VR_FET_SW_P12V_STBY_PVPP_DEF")
		)
		(pad "2" smd rect
			(at 0 1.778)
			(size 1.27 1.016)
			(layers "B.Cu" "B.Mask" "B.Paste")
			(net "GND")
		)
		(zone
			(layer "B.Cu")
			(hatch none 0.5)
			(connect_pads
				(clearance 0)
			)
			(min_thickness 0.25)
			(keepout
				(tracks not_allowed)
				(vias allowed)
				(pads allowed)
				(copperpour not_allowed)
				(footprints allowed)
			)
			(placement
				(enabled no)
				(sheetname "")
			)
			(fill
				(thermal_gap 0.5)
				(thermal_bridge_width 0.5)
				(island_removal_mode 0)
			)
			(polygon
				(pts
					(xy 351.028 -133.731) (xy 352.298 -133.731) (xy 352.298 -134.493) (xy 351.028 -134.493)
				)
			)
		)
	)
	(footprint ""
		(layer "B.Cu")
		(at 352.904806 -60.368434)
		(property "Reference" "R2U28"
			(at 0 0 0)
			(layer "B.SilkS")
			(hide yes)
			(effects
				(font
					(size 1.27 1.27)
				)
				(justify mirror)
			)
		)
		(property "Value" ""
			(at 0 0 0)
			(layer "B.Fab")
			(effects
				(font
					(size 1.27 1.27)
				)
				(justify mirror)
			)
		)
		(duplicate_pad_numbers_are_jumpers no)
		(fp_poly
			(pts
				(xy 0.2794 -0.1016) (xy -0.2794 -0.1016) (xy -0.2794 0.9906) (xy 0.2794 0.9906)
			)
			(stroke
				(width 0)
				(type default)
			)
			(fill no)
			(layer "B.CrtYd")
		)
		(fp_line
			(start -0.2794 -0.1016)
			(end 0.2794 -0.1016)
			(stroke
				(width 0.1)
				(type default)
			)
			(layer "B.Fab")
		)
		(fp_line
			(start -0.2794 0.9906)
			(end -0.2794 -0.1016)
			(stroke
				(width 0.1)
				(type default)
			)
			(layer "B.Fab")
		)
		(fp_line
			(start 0.2794 -0.1016)
			(end 0.2794 0.9906)
			(stroke
				(width 0.1)
				(type default)
			)
			(layer "B.Fab")
		)
		(fp_line
			(start 0.2794 0.9906)
			(end -0.2794 0.9906)
			(stroke
				(width 0.1)
				(type default)
			)
			(layer "B.Fab")
		)
		(pad "1" smd rect
			(at 0 0 180)
			(size 0.508 0.508)
			(layers "B.Cu" "B.Mask" "B.Paste")
			(net "P3E_CPU0_PE1_SS_RXP<7>")
		)
		(pad "2" smd rect
			(at 0 0.889 180)
			(size 0.508 0.508)
			(layers "B.Cu" "B.Mask" "B.Paste")
			(net "P3E_CPU0_PE1_SS_R_RXP<7>")
		)
		(zone
			(layer "B.Cu")
			(hatch none 0.5)
			(connect_pads
				(clearance 0)
			)
			(min_thickness 0.25)
			(keepout
				(tracks allowed)
				(vias not_allowed)
				(pads allowed)
				(copperpour not_allowed)
				(footprints allowed)
			)
			(placement
				(enabled no)
				(sheetname "")
			)
			(fill
				(thermal_gap 0.5)
				(thermal_bridge_width 0.5)
				(island_removal_mode 0)
			)
			(polygon
				(pts
					(xy 353.158806 -60.114434) (xy 352.650806 -60.114434) (xy 352.650806 -59.733434) (xy 353.158806 -59.733434)
				)
			)
		)
		(zone
			(layer "B.Cu")
			(hatch none 0.5)
			(connect_pads
				(clearance 0)
			)
			(min_thickness 0.25)
			(keepout
				(tracks not_allowed)
				(vias allowed)
				(pads allowed)
				(copperpour not_allowed)
				(footprints allowed)
			)
			(placement
				(enabled no)
				(sheetname "")
			)
			(fill
				(thermal_gap 0.5)
				(thermal_bridge_width 0.5)
				(island_removal_mode 0)
			)
			(polygon
				(pts
					(xy 353.158806 -59.733434) (xy 352.650806 -59.733434) (xy 352.650806 -60.114434) (xy 353.158806 -60.114434)
				)
			)
		)
	)
	(footprint ""
		(layer "B.Cu")
		(at 210.612228 -100.676202 -90)
		(property "Reference" "C6N1"
			(at -1.659128 -3.382772 0)
			(unlocked yes)
			(layer "B.SilkS")
			(effects
				(font
					(size 0.7874 0.5842)
					(thickness 0.1524)
				)
				(justify mirror)
			)
		)
		(property "Value" ""
			(at 0 0 90)
			(layer "B.Fab")
			(effects
				(font
					(size 1.27 1.27)
				)
				(justify mirror)
			)
		)
		(duplicate_pad_numbers_are_jumpers no)
		(fp_line
			(start -2.286 7.366)
			(end -1.600708 7.366)
			(stroke
				(width 0.1524)
				(type default)
			)
			(layer "B.SilkS")
		)
		(fp_line
			(start -2.286 7.366)
			(end -2.286 1.63195)
			(stroke
				(width 0.1524)
				(type default)
			)
			(layer "B.SilkS")
		)
		(fp_line
			(start 2.286 7.366)
			(end 1.60147 7.366)
			(stroke
				(width 0.1524)
				(type default)
			)
			(layer "B.SilkS")
		)
		(fp_line
			(start 2.286 7.366)
			(end 2.286 1.632712)
			(stroke
				(width 0.1524)
				(type default)
			)
			(layer "B.SilkS")
		)
		(fp_line
			(start -2.504948 1.633728)
			(end -1.6002 1.633728)
			(stroke
				(width 0.1524)
				(type default)
			)
			(layer "B.SilkS")
		)
		(fp_line
			(start 2.563114 1.633728)
			(end 1.6002 1.633728)
			(stroke
				(width 0.1524)
				(type default)
			)
			(layer "B.SilkS")
		)
		(fp_line
			(start -2.504948 -1.616456)
			(end -2.504948 1.633728)
			(stroke
				(width 0.1524)
				(type default)
			)
			(layer "B.SilkS")
		)
		(fp_line
			(start -1.6002 -1.616456)
			(end -2.504948 -1.616456)
			(stroke
				(width 0.1524)
				(type default)
			)
			(layer "B.SilkS")
		)
		(fp_line
			(start 1.6002 -1.616456)
			(end 2.563114 -1.616456)
			(stroke
				(width 0.1524)
				(type default)
			)
			(layer "B.SilkS")
		)
		(fp_line
			(start 2.563114 -1.616456)
			(end 2.563114 1.633728)
			(stroke
				(width 0.1524)
				(type default)
			)
			(layer "B.SilkS")
		)
		(fp_rect
			(start 2.286 7.366)
			(end -2.286 -0.254)
			(stroke
				(width 0)
				(type default)
			)
			(fill no)
			(layer "B.CrtYd")
		)
		(fp_line
			(start -2.286 7.366)
			(end 2.286 7.366)
			(stroke
				(width 0.1)
				(type default)
			)
			(layer "B.Fab")
		)
		(fp_line
			(start 2.286 7.366)
			(end 2.286 -0.254)
			(stroke
				(width 0.1)
				(type default)
			)
			(layer "B.Fab")
		)
		(fp_line
			(start -2.286 -0.254)
			(end -2.286 7.366)
			(stroke
				(width 0.1)
				(type default)
			)
			(layer "B.Fab")
		)
		(fp_line
			(start 2.286 -0.254)
			(end -2.286 -0.254)
			(stroke
				(width 0.1)
				(type default)
			)
			(layer "B.Fab")
		)
		(pad "1" smd rect
			(at 0 0 90)
			(size 2.54 3.048)
			(layers "B.Cu" "B.Mask" "B.Paste")
			(net "PVSA_CPU0")
		)
		(pad "2" smd rect
			(at 0 7.112 90)
			(size 2.54 3.048)
			(layers "B.Cu" "B.Mask" "B.Paste")
			(net "GND")
		)
	)
)
